# T6G (Grand Teton) — schematic netlist excerpt (pin names and nets, part order shuffled) for the footprints in the layout excerpt that follows; sources: Cadence DE-HDL packaged netlist, KiCad conversion of 04192023_DAF0TMB3IC0_F0TG_MB_C_brd_V02_OCP.brd

R3778  Q_RES  0 5% CHIP  pkg 0402LF  page 150 : A = FM_SOL_UART_CH_SEL_R ; B = FM_SOL_UART_CH_SEL
C6692  Q_CAP_DIFFBUS  DIFF BUS_0.22UF 6.3V 20% X6S  pkg C0201  page 330 : \1\ = P5E_CPU1_P1_TX_BUF_C_DN<15> ; \2\ = P5E_CPU1_P1_TX_BUF_DN<15>
C7017  Q_CAPP  470UF 2.5V 20% SPCAP  pkg SMLF  page 312 : A = P0V9_CPU0_RT3_2A ; B = GND

(kicad_pcb
	(version 20260206)
	(generator "pcbnew")
	(generator_version "10.0")
	(general
		(thickness 1.6)
		(legacy_teardrops no)
	)
	(paper "A4")
	(title_block
		(title "04192023_DAF0TMB3IC0_F0TG_MB_C_brd_V02_OCP.brd")
		(comment 1 "Grand Teton / footprints 5866-5868 of 8354")
	)
	(layers
		(0 "F.Cu" signal "TOP")
		(4 "In1.Cu" signal "GND")
		(6 "In2.Cu" signal "IN1")
		(8 "In3.Cu" signal "GND1")
		(10 "In4.Cu" signal "IN2")
		(12 "In5.Cu" signal "GND2")
		(14 "In6.Cu" signal "IN3")
		(16 "In7.Cu" signal "GND3")
		(18 "In8.Cu" signal "VCC")
		(20 "In9.Cu" signal "VCC1")
		(22 "In10.Cu" signal "GND4")
		(24 "In11.Cu" signal "IN4")
		(26 "In12.Cu" signal "GND5")
		(28 "In13.Cu" signal "IN5")
		(30 "In14.Cu" signal "GND6")
		(32 "In15.Cu" signal "IN6")
		(34 "In16.Cu" signal "GND7")
		(2 "B.Cu" signal "BOTTOM")
		(9 "F.Adhes" user "F.Adhesive")
		(11 "B.Adhes" user "B.Adhesive")
		(13 "F.Paste" user "Package Geometry/Pastemask Top")
		(15 "B.Paste" user "Package Geometry/Pastemask Bottom")
		(5 "F.SilkS" user "Ref Des/Silkscreen Top")
		(7 "B.SilkS" user "Ref Des/Silkscreen Bottom")
		(1 "F.Mask" user "Board Geometry/Soldermask Top")
		(3 "B.Mask" user "Board Geometry/Soldermask Bottom")
		(17 "Dwgs.User" user "User.Drawings")
		(19 "Cmts.User" user "User.Comments")
		(21 "Eco1.User" user "User.Eco1")
		(23 "Eco2.User" user "User.Eco2")
		(25 "Edge.Cuts" user "Board Geometry/Outline")
		(27 "Margin" user)
		(31 "F.CrtYd" user "Package Geometry/Place Bound Top")
		(29 "B.CrtYd" user "Package Geometry/Place Bound Bottom")
		(35 "F.Fab" user "Ref Des/Assembly Top")
		(33 "B.Fab" user "Ref Des/Assembly Bottom")
	)
	(footprint ""
		(layer "B.Cu")
		(at 375.597166 -389.49503 180)
		(property "Reference" "C7017"
			(at -1.554988 -3.243072 0)
			(unlocked yes)
			(layer "B.SilkS")
			(effects
				(font
					(size 0.7874 0.5842)
					(thickness 0.1524)
				)
				(justify left mirror)
			)
		)
		(property "Value" ""
			(at 0 0 0)
			(layer "B.Fab")
			(effects
				(font
					(size 1.27 1.27)
				)
				(justify mirror)
			)
		)
		(duplicate_pad_numbers_are_jumpers no)
		(fp_line
			(start 4.84378 -2.150618)
			(end 4.842256 2.163064)
			(stroke
				(width 0.1524)
				(type default)
			)
			(layer "B.SilkS")
		)
		(fp_line
			(start 4.84378 -2.150618)
			(end 4.53898 -2.150618)
			(stroke
				(width 0.1524)
				(type default)
			)
			(layer "B.SilkS")
		)
		(fp_line
			(start 4.83108 2.150364)
			(end 4.447794 2.149348)
			(stroke
				(width 0.1524)
				(type default)
			)
			(layer "B.SilkS")
		)
		(fp_line
			(start 4.69138 -2.150618)
			(end 4.692396 2.161032)
			(stroke
				(width 0.1524)
				(type default)
			)
			(layer "B.SilkS")
		)
		(fp_line
			(start 4.53898 2.15011)
			(end 4.53898 -2.15011)
			(stroke
				(width 0.1524)
				(type default)
			)
			(layer "B.SilkS")
		)
		(fp_line
			(start 4.53898 -2.15011)
			(end -4.53898 -2.15011)
			(stroke
				(width 0.1524)
				(type default)
			)
			(layer "B.SilkS")
		)
		(fp_line
			(start 4.53898 -2.150618)
			(end 4.539742 2.152142)
			(stroke
				(width 0.1524)
				(type default)
			)
			(layer "B.SilkS")
		)
		(fp_line
			(start -4.53898 2.15011)
			(end 4.53898 2.15011)
			(stroke
				(width 0.1524)
				(type default)
			)
			(layer "B.SilkS")
		)
		(fp_line
			(start -4.53898 -2.15011)
			(end -4.53898 2.15011)
			(stroke
				(width 0.1524)
				(type default)
			)
			(layer "B.SilkS")
		)
		(fp_line
			(start 3.64998 2.15011)
			(end 3.64998 -2.15011)
			(stroke
				(width 0.1)
				(type default)
			)
			(layer "B.Fab")
		)
		(fp_line
			(start 3.64998 -2.15011)
			(end -3.64998 -2.15011)
			(stroke
				(width 0.1)
				(type default)
			)
			(layer "B.Fab")
		)
		(fp_line
			(start -3.64998 2.15011)
			(end 3.64998 2.15011)
			(stroke
				(width 0.1)
				(type default)
			)
			(layer "B.Fab")
		)
		(fp_line
			(start -3.64998 -2.15011)
			(end -3.64998 2.15011)
			(stroke
				(width 0.1)
				(type default)
			)
			(layer "B.Fab")
		)
		(fp_text user "+"
			(at 4.233672 -3.049778 180)
			(unlocked yes)
			(layer "B.SilkS")
			(effects
				(font
					(size 1.905 1.4224)
					(thickness 0.1524)
				)
				(justify left mirror)
			)
		)
		(fp_text user "-"
			(at -2.707894 -2.736088 180)
			(unlocked yes)
			(layer "B.SilkS")
			(effects
				(font
					(size 1.905 1.4224)
					(thickness 0.1524)
				)
				(justify left mirror)
			)
		)
		(fp_text user "+"
			(at 6.214872 -0.337058 180)
			(unlocked yes)
			(layer "B.Fab")
			(effects
				(font
					(size 1.905 1.4224)
					(thickness 0.1524)
				)
				(justify left mirror)
			)
		)
		(fp_text user "-"
			(at -4.313174 -0.094488 180)
			(unlocked yes)
			(layer "B.Fab")
			(effects
				(font
					(size 1.905 1.4224)
					(thickness 0.1524)
				)
				(justify left mirror)
			)
		)
		(pad "1" smd rect
			(at 3.199892 0)
			(size 2.413 2.8194)
			(layers "B.Cu" "B.Mask" "B.Paste")
			(net "P0V9_CPU0_RT3_2A")
		)
		(pad "2" smd rect
			(at -3.199892 0)
			(size 2.413 2.8194)
			(layers "B.Cu" "B.Mask" "B.Paste")
			(net "GND")
		)
	)
	(footprint ""
		(layer "B.Cu")
		(at 180.162962 -13.896594 90)
		(property "Reference" "R3778"
			(at 0 0 90)
			(layer "B.SilkS")
			(hide yes)
			(effects
				(font
					(size 1.27 1.27)
				)
				(justify mirror)
			)
		)
		(property "Value" ""
			(at 0 0 90)
			(layer "B.Fab")
			(effects
				(font
					(size 1.27 1.27)
				)
				(justify mirror)
			)
		)
		(duplicate_pad_numbers_are_jumpers no)
		(fp_line
			(start 0.7874 -0.4064)
			(end -0.7874 -0.4064)
			(stroke
				(width 0.1524)
				(type default)
			)
			(layer "B.SilkS")
		)
		(fp_line
			(start -0.7874 -0.4064)
			(end -0.7874 0.4064)
			(stroke
				(width 0.1524)
				(type default)
			)
			(layer "B.SilkS")
		)
		(fp_line
			(start 0.7874 0.4064)
			(end 0.7874 -0.4064)
			(stroke
				(width 0.1524)
				(type default)
			)
			(layer "B.SilkS")
		)
		(fp_line
			(start -0.7874 0.4064)
			(end 0.7874 0.4064)
			(stroke
				(width 0.1524)
				(type default)
			)
			(layer "B.SilkS")
		)
		(fp_line
			(start 0.67945 -0.305054)
			(end 0.12065 -0.305054)
			(stroke
				(width 0.1)
				(type default)
			)
			(layer "B.Fab")
		)
		(fp_line
			(start 0.12065 -0.305054)
			(end 0.12065 -0.2794)
			(stroke
				(width 0.1)
				(type default)
			)
			(layer "B.Fab")
		)
		(fp_line
			(start -0.12065 -0.3048)
			(end -0.67945 -0.3048)
			(stroke
				(width 0.1)
				(type default)
			)
			(layer "B.Fab")
		)
		(fp_line
			(start -0.67945 -0.3048)
			(end -0.67945 0.3048)
			(stroke
				(width 0.1)
				(type default)
			)
			(layer "B.Fab")
		)
		(fp_line
			(start 0.12065 -0.2794)
			(end -0.12065 -0.2794)
			(stroke
				(width 0.1)
				(type default)
			)
			(layer "B.Fab")
		)
		(fp_line
			(start -0.12065 -0.2794)
			(end -0.12065 -0.3048)
			(stroke
				(width 0.1)
				(type default)
			)
			(layer "B.Fab")
		)
		(fp_line
			(start 0.12065 0.2794)
			(end 0.12065 0.3048)
			(stroke
				(width 0.1)
				(type default)
			)
			(layer "B.Fab")
		)
		(fp_line
			(start -0.120396 0.2794)
			(end 0.12065 0.2794)
			(stroke
				(width 0.1)
				(type default)
			)
			(layer "B.Fab")
		)
		(fp_line
			(start 0.67945 0.3048)
			(end 0.67945 -0.305054)
			(stroke
				(width 0.1)
				(type default)
			)
			(layer "B.Fab")
		)
		(fp_line
			(start 0.12065 0.3048)
			(end 0.67945 0.3048)
			(stroke
				(width 0.1)
				(type default)
			)
			(layer "B.Fab")
		)
		(fp_line
			(start -0.120396 0.3048)
			(end -0.120396 0.2794)
			(stroke
				(width 0.1)
				(type default)
			)
			(layer "B.Fab")
		)
		(fp_line
			(start -0.67945 0.3048)
			(end -0.120396 0.3048)
			(stroke
				(width 0.1)
				(type default)
			)
			(layer "B.Fab")
		)
		(pad "1" smd circle
			(at 0.40005 0 270)
			(size 0 0)
			(layers "B.Cu" "B.Mask" "B.Paste")
			(net "FM_SOL_UART_CH_SEL_R")
		)
		(pad "2" smd circle
			(at -0.40005 0 270)
			(size 0 0)
			(layers "B.Cu" "B.Mask" "B.Paste")
			(net "FM_SOL_UART_CH_SEL")
		)
	)
	(footprint ""
		(layer "B.Cu")
		(at 95.248984 -408.517344 90)
		(property "Reference" "C6692"
			(at 0 0 90)
			(layer "B.SilkS")
			(hide yes)
			(effects
				(font
					(size 1.27 1.27)
				)
				(justify mirror)
			)
		)
		(property "Value" ""
			(at 0 0 90)
			(layer "B.Fab")
			(effects
				(font
					(size 1.27 1.27)
				)
				(justify mirror)
			)
		)
		(duplicate_pad_numbers_are_jumpers no)
		(fp_line
			(start 0.299974 -0.150114)
			(end -0.299974 -0.150114)
			(stroke
				(width 0.1)
				(type default)
			)
			(layer "B.Fab")
		)
		(fp_line
			(start -0.299974 -0.150114)
			(end -0.299974 0.150114)
			(stroke
				(width 0.1)
				(type default)
			)
			(layer "B.Fab")
		)
		(fp_line
			(start 0.299974 0.150114)
			(end 0.299974 -0.150114)
			(stroke
				(width 0.1)
				(type default)
			)
			(layer "B.Fab")
		)
		(fp_line
			(start -0.299974 0.150114)
			(end 0.299974 0.150114)
			(stroke
				(width 0.1)
				(type default)
			)
			(layer "B.Fab")
		)
		(pad "1" smd rect
			(at 0.2667 0 270)
			(size 0.3048 0.381)
			(layers "B.Cu" "B.Mask" "B.Paste")
			(net "P5E_CPU1_P1_TX_BUF_C_DN<15>")
		)
		(pad "2" smd rect
			(at -0.2667 0 270)
			(size 0.3048 0.381)
			(layers "B.Cu" "B.Mask" "B.Paste")
			(net "P5E_CPU1_P1_TX_BUF_DN<15>")
		)
	)
)
